(kicad_pcb
	(version 20260206)
	(generator "pcbnew")
	(generator_version "10.0")
	(general
		(thickness 1.6)
		(legacy_teardrops no)
	)
	(paper "A4")
	(title_block
		(title "12092022_DA0F0TMDCD0_F0T_Management_Board_D_brd_V3_OCP.brd")
		(comment 1 "Grand Teton / footprints 644-649 of 1440")
	)
	(layers
		(0 "F.Cu" signal "TOP")
		(4 "In1.Cu" signal "GND")
		(6 "In2.Cu" signal "IN1")
		(8 "In3.Cu" signal "GND1")
		(10 "In4.Cu" signal "IN2")
		(12 "In5.Cu" signal "VCC")
		(14 "In6.Cu" signal "VCC1")
		(16 "In7.Cu" signal "IN3")
		(18 "In8.Cu" signal "GND2")
		(20 "In9.Cu" signal "IN4")
		(22 "In10.Cu" signal "GND3")
		(2 "B.Cu" signal "BOTTOM")
		(9 "F.Adhes" user "F.Adhesive")
		(11 "B.Adhes" user "B.Adhesive")
		(13 "F.Paste" user "Package Geometry/Pastemask Top")
		(15 "B.Paste" user "Package Geometry/Pastemask Bottom")
		(5 "F.SilkS" user "Ref Des/Silkscreen Top")
		(7 "B.SilkS" user "Ref Des/Silkscreen Bottom")
		(1 "F.Mask" user "Board Geometry/Soldermask Top")
		(3 "B.Mask" user "Board Geometry/Soldermask Bottom")
		(17 "Dwgs.User" user "User.Drawings")
		(19 "Cmts.User" user "User.Comments")
		(21 "Eco1.User" user "User.Eco1")
		(23 "Eco2.User" user "User.Eco2")
		(25 "Edge.Cuts" user "Board Geometry/Outline")
		(27 "Margin" user)
		(31 "F.CrtYd" user "Package Geometry/Place Bound Top")
		(29 "B.CrtYd" user "Package Geometry/Place Bound Bottom")
		(35 "F.Fab" user "Ref Des/Assembly Top")
		(33 "B.Fab" user "Ref Des/Assembly Bottom")
	)
	(footprint ""
		(layer "F.Cu")
		(at 56.7182 -30.861 90)
		(property "Reference" "R840"
			(at 0 0 90)
			(layer "F.SilkS")
			(hide yes)
			(effects
				(font
					(size 1.27 1.27)
				)
			)
		)
		(property "Value" ""
			(at 0 0 90)
			(layer "F.Fab")
			(effects
				(font
					(size 1.27 1.27)
				)
			)
		)
		(duplicate_pad_numbers_are_jumpers no)
		(fp_line
			(start 0.7874 -0.4064)
			(end 0.7874 0.4064)
			(stroke
				(width 0.1524)
				(type default)
			)
			(layer "F.SilkS")
		)
		(fp_line
			(start -0.7874 -0.4064)
			(end 0.7874 -0.4064)
			(stroke
				(width 0.1524)
				(type default)
			)
			(layer "F.SilkS")
		)
		(fp_line
			(start 0.7874 0.4064)
			(end -0.7874 0.4064)
			(stroke
				(width 0.1524)
				(type default)
			)
			(layer "F.SilkS")
		)
		(fp_line
			(start -0.7874 0.4064)
			(end -0.7874 -0.4064)
			(stroke
				(width 0.1524)
				(type default)
			)
			(layer "F.SilkS")
		)
		(fp_line
			(start -0.12065 -0.305054)
			(end -0.12065 -0.2794)
			(stroke
				(width 0.1)
				(type default)
			)
			(layer "F.Fab")
		)
		(fp_line
			(start -0.67945 -0.305054)
			(end -0.12065 -0.305054)
			(stroke
				(width 0.1)
				(type default)
			)
			(layer "F.Fab")
		)
		(fp_line
			(start 0.67945 -0.3048)
			(end 0.67945 0.3048)
			(stroke
				(width 0.1)
				(type default)
			)
			(layer "F.Fab")
		)
		(fp_line
			(start 0.12065 -0.3048)
			(end 0.67945 -0.3048)
			(stroke
				(width 0.1)
				(type default)
			)
			(layer "F.Fab")
		)
		(fp_line
			(start 0.12065 -0.2794)
			(end 0.12065 -0.3048)
			(stroke
				(width 0.1)
				(type default)
			)
			(layer "F.Fab")
		)
		(fp_line
			(start -0.12065 -0.2794)
			(end 0.12065 -0.2794)
			(stroke
				(width 0.1)
				(type default)
			)
			(layer "F.Fab")
		)
		(fp_line
			(start 0.120396 0.2794)
			(end -0.12065 0.2794)
			(stroke
				(width 0.1)
				(type default)
			)
			(layer "F.Fab")
		)
		(fp_line
			(start -0.12065 0.2794)
			(end -0.12065 0.3048)
			(stroke
				(width 0.1)
				(type default)
			)
			(layer "F.Fab")
		)
		(fp_line
			(start 0.67945 0.3048)
			(end 0.120396 0.3048)
			(stroke
				(width 0.1)
				(type default)
			)
			(layer "F.Fab")
		)
		(fp_line
			(start 0.120396 0.3048)
			(end 0.120396 0.2794)
			(stroke
				(width 0.1)
				(type default)
			)
			(layer "F.Fab")
		)
		(fp_line
			(start -0.12065 0.3048)
			(end -0.67945 0.3048)
			(stroke
				(width 0.1)
				(type default)
			)
			(layer "F.Fab")
		)
		(fp_line
			(start -0.67945 0.3048)
			(end -0.67945 -0.305054)
			(stroke
				(width 0.1)
				(type default)
			)
			(layer "F.Fab")
		)
		(pad "1" smd circle
			(at -0.40005 0 90)
			(size 0 0)
			(layers "F.Cu" "F.Mask" "F.Paste")
			(net "PWRGD_SYS_PWROK")
		)
		(pad "2" smd circle
			(at 0.40005 0 90)
			(size 0 0)
			(layers "F.Cu" "F.Mask" "F.Paste")
			(net "PWRGD_SYS_PWROK_BMC")
		)
	)
	(footprint ""
		(layer "F.Cu")
		(at 39.751 -34.036 -90)
		(property "Reference" "R214"
			(at 0 0 270)
			(layer "F.SilkS")
			(hide yes)
			(effects
				(font
					(size 1.27 1.27)
				)
			)
		)
		(property "Value" ""
			(at 0 0 270)
			(layer "F.Fab")
			(effects
				(font
					(size 1.27 1.27)
				)
			)
		)
		(duplicate_pad_numbers_are_jumpers no)
		(fp_line
			(start -0.7874 0.4064)
			(end -0.7874 -0.4064)
			(stroke
				(width 0.1524)
				(type default)
			)
			(layer "F.SilkS")
		)
		(fp_line
			(start 0.7874 0.4064)
			(end -0.7874 0.4064)
			(stroke
				(width 0.1524)
				(type default)
			)
			(layer "F.SilkS")
		)
		(fp_line
			(start -0.7874 -0.4064)
			(end 0.7874 -0.4064)
			(stroke
				(width 0.1524)
				(type default)
			)
			(layer "F.SilkS")
		)
		(fp_line
			(start 0.7874 -0.4064)
			(end 0.7874 0.4064)
			(stroke
				(width 0.1524)
				(type default)
			)
			(layer "F.SilkS")
		)
		(fp_line
			(start -0.67945 0.3048)
			(end -0.67945 -0.305054)
			(stroke
				(width 0.1)
				(type default)
			)
			(layer "F.Fab")
		)
		(fp_line
			(start -0.12065 0.3048)
			(end -0.67945 0.3048)
			(stroke
				(width 0.1)
				(type default)
			)
			(layer "F.Fab")
		)
		(fp_line
			(start 0.120396 0.3048)
			(end 0.120396 0.2794)
			(stroke
				(width 0.1)
				(type default)
			)
			(layer "F.Fab")
		)
		(fp_line
			(start 0.67945 0.3048)
			(end 0.120396 0.3048)
			(stroke
				(width 0.1)
				(type default)
			)
			(layer "F.Fab")
		)
		(fp_line
			(start -0.12065 0.2794)
			(end -0.12065 0.3048)
			(stroke
				(width 0.1)
				(type default)
			)
			(layer "F.Fab")
		)
		(fp_line
			(start 0.120396 0.2794)
			(end -0.12065 0.2794)
			(stroke
				(width 0.1)
				(type default)
			)
			(layer "F.Fab")
		)
		(fp_line
			(start -0.12065 -0.2794)
			(end 0.12065 -0.2794)
			(stroke
				(width 0.1)
				(type default)
			)
			(layer "F.Fab")
		)
		(fp_line
			(start 0.12065 -0.2794)
			(end 0.12065 -0.3048)
			(stroke
				(width 0.1)
				(type default)
			)
			(layer "F.Fab")
		)
		(fp_line
			(start 0.12065 -0.3048)
			(end 0.67945 -0.3048)
			(stroke
				(width 0.1)
				(type default)
			)
			(layer "F.Fab")
		)
		(fp_line
			(start 0.67945 -0.3048)
			(end 0.67945 0.3048)
			(stroke
				(width 0.1)
				(type default)
			)
			(layer "F.Fab")
		)
		(fp_line
			(start -0.67945 -0.305054)
			(end -0.12065 -0.305054)
			(stroke
				(width 0.1)
				(type default)
			)
			(layer "F.Fab")
		)
		(fp_line
			(start -0.12065 -0.305054)
			(end -0.12065 -0.2794)
			(stroke
				(width 0.1)
				(type default)
			)
			(layer "F.Fab")
		)
		(pad "1" smd circle
			(at -0.40005 0 270)
			(size 0 0)
			(layers "F.Cu" "F.Mask" "F.Paste")
			(net "P1V8_AUX")
		)
		(pad "2" smd circle
			(at 0.40005 0 270)
			(size 0 0)
			(layers "F.Cu" "F.Mask" "F.Paste")
			(net "P3V3_P1V8_SD2VDD")
		)
	)
	(footprint ""
		(layer "F.Cu")
		(at 53.12156 -62.2046 180)
		(property "Reference" "R678"
			(at 0 0 180)
			(layer "F.SilkS")
			(hide yes)
			(effects
				(font
					(size 1.27 1.27)
				)
			)
		)
		(property "Value" ""
			(at 0 0 180)
			(layer "F.Fab")
			(effects
				(font
					(size 1.27 1.27)
				)
			)
		)
		(duplicate_pad_numbers_are_jumpers no)
		(fp_line
			(start 0.7874 0.4064)
			(end -0.7874 0.4064)
			(stroke
				(width 0.1524)
				(type default)
			)
			(layer "F.SilkS")
		)
		(fp_line
			(start 0.7874 -0.4064)
			(end 0.7874 0.4064)
			(stroke
				(width 0.1524)
				(type default)
			)
			(layer "F.SilkS")
		)
		(fp_line
			(start -0.7874 0.4064)
			(end -0.7874 -0.4064)
			(stroke
				(width 0.1524)
				(type default)
			)
			(layer "F.SilkS")
		)
		(fp_line
			(start -0.7874 -0.4064)
			(end 0.7874 -0.4064)
			(stroke
				(width 0.1524)
				(type default)
			)
			(layer "F.SilkS")
		)
		(fp_line
			(start 0.67945 0.3048)
			(end 0.120396 0.3048)
			(stroke
				(width 0.1)
				(type default)
			)
			(layer "F.Fab")
		)
		(fp_line
			(start 0.67945 -0.3048)
			(end 0.67945 0.3048)
			(stroke
				(width 0.1)
				(type default)
			)
			(layer "F.Fab")
		)
		(fp_line
			(start 0.12065 -0.2794)
			(end 0.12065 -0.3048)
			(stroke
				(width 0.1)
				(type default)
			)
			(layer "F.Fab")
		)
		(fp_line
			(start 0.12065 -0.3048)
			(end 0.67945 -0.3048)
			(stroke
				(width 0.1)
				(type default)
			)
			(layer "F.Fab")
		)
		(fp_line
			(start 0.120396 0.3048)
			(end 0.120396 0.2794)
			(stroke
				(width 0.1)
				(type default)
			)
			(layer "F.Fab")
		)
		(fp_line
			(start 0.120396 0.2794)
			(end -0.12065 0.2794)
			(stroke
				(width 0.1)
				(type default)
			)
			(layer "F.Fab")
		)
		(fp_line
			(start -0.12065 0.3048)
			(end -0.67945 0.3048)
			(stroke
				(width 0.1)
				(type default)
			)
			(layer "F.Fab")
		)
		(fp_line
			(start -0.12065 0.2794)
			(end -0.12065 0.3048)
			(stroke
				(width 0.1)
				(type default)
			)
			(layer "F.Fab")
		)
		(fp_line
			(start -0.12065 -0.2794)
			(end 0.12065 -0.2794)
			(stroke
				(width 0.1)
				(type default)
			)
			(layer "F.Fab")
		)
		(fp_line
			(start -0.12065 -0.305054)
			(end -0.12065 -0.2794)
			(stroke
				(width 0.1)
				(type default)
			)
			(layer "F.Fab")
		)
		(fp_line
			(start -0.67945 0.3048)
			(end -0.67945 -0.305054)
			(stroke
				(width 0.1)
				(type default)
			)
			(layer "F.Fab")
		)
		(fp_line
			(start -0.67945 -0.305054)
			(end -0.12065 -0.305054)
			(stroke
				(width 0.1)
				(type default)
			)
			(layer "F.Fab")
		)
		(pad "1" smd circle
			(at -0.40005 0 180)
			(size 0 0)
			(layers "F.Cu" "F.Mask" "F.Paste")
			(net "SPI_BMC_CLK_R")
		)
		(pad "2" smd circle
			(at 0.40005 0 180)
			(size 0 0)
			(layers "F.Cu" "F.Mask" "F.Paste")
			(net "QSPI_2_PLD_CLK")
		)
	)
	(footprint ""
		(layer "F.Cu")
		(at 85.2932 -18.796)
		(property "Reference" "C199"
			(at 0 0 0)
			(layer "F.SilkS")
			(hide yes)
			(effects
				(font
					(size 1.27 1.27)
				)
			)
		)
		(property "Value" ""
			(at 0 0 0)
			(layer "F.Fab")
			(effects
				(font
					(size 1.27 1.27)
				)
			)
		)
		(duplicate_pad_numbers_are_jumpers no)
		(fp_line
			(start -0.7874 -0.4064)
			(end 0.7874 -0.4064)
			(stroke
				(width 0.1524)
				(type default)
			)
			(layer "F.SilkS")
		)
		(fp_line
			(start -0.7874 0.4064)
			(end -0.7874 -0.4064)
			(stroke
				(width 0.1524)
				(type default)
			)
			(layer "F.SilkS")
		)
		(fp_line
			(start 0.7874 -0.4064)
			(end 0.7874 0.4064)
			(stroke
				(width 0.1524)
				(type default)
			)
			(layer "F.SilkS")
		)
		(fp_line
			(start 0.7874 0.4064)
			(end -0.7874 0.4064)
			(stroke
				(width 0.1524)
				(type default)
			)
			(layer "F.SilkS")
		)
		(fp_line
			(start -0.67945 -0.305054)
			(end -0.12065 -0.305054)
			(stroke
				(width 0.1)
				(type default)
			)
			(layer "F.Fab")
		)
		(fp_line
			(start -0.67945 0.3048)
			(end -0.67945 -0.305054)
			(stroke
				(width 0.1)
				(type default)
			)
			(layer "F.Fab")
		)
		(fp_line
			(start -0.12065 -0.305054)
			(end -0.12065 -0.2794)
			(stroke
				(width 0.1)
				(type default)
			)
			(layer "F.Fab")
		)
		(fp_line
			(start -0.12065 -0.2794)
			(end 0.12065 -0.2794)
			(stroke
				(width 0.1)
				(type default)
			)
			(layer "F.Fab")
		)
		(fp_line
			(start -0.12065 0.2794)
			(end -0.12065 0.3048)
			(stroke
				(width 0.1)
				(type default)
			)
			(layer "F.Fab")
		)
		(fp_line
			(start -0.12065 0.3048)
			(end -0.67945 0.3048)
			(stroke
				(width 0.1)
				(type default)
			)
			(layer "F.Fab")
		)
		(fp_line
			(start 0.120396 0.2794)
			(end -0.12065 0.2794)
			(stroke
				(width 0.1)
				(type default)
			)
			(layer "F.Fab")
		)
		(fp_line
			(start 0.120396 0.3048)
			(end 0.120396 0.2794)
			(stroke
				(width 0.1)
				(type default)
			)
			(layer "F.Fab")
		)
		(fp_line
			(start 0.12065 -0.3048)
			(end 0.67945 -0.3048)
			(stroke
				(width 0.1)
				(type default)
			)
			(layer "F.Fab")
		)
		(fp_line
			(start 0.12065 -0.2794)
			(end 0.12065 -0.3048)
			(stroke
				(width 0.1)
				(type default)
			)
			(layer "F.Fab")
		)
		(fp_line
			(start 0.67945 -0.3048)
			(end 0.67945 0.3048)
			(stroke
				(width 0.1)
				(type default)
			)
			(layer "F.Fab")
		)
		(fp_line
			(start 0.67945 0.3048)
			(end 0.120396 0.3048)
			(stroke
				(width 0.1)
				(type default)
			)
			(layer "F.Fab")
		)
		(pad "1" smd circle
			(at -0.40005 0)
			(size 0 0)
			(layers "F.Cu" "F.Mask" "F.Paste")
			(net "REAR_ID_RST_BTN_N")
		)
		(pad "2" smd circle
			(at 0.40005 0)
			(size 0 0)
			(layers "F.Cu" "F.Mask" "F.Paste")
			(net "GND")
		)
	)
	(footprint ""
		(layer "F.Cu")
		(at 55.184548 -34.637726 -90)
		(property "Reference" "R582"
			(at 0 0 270)
			(layer "F.SilkS")
			(hide yes)
			(effects
				(font
					(size 1.27 1.27)
				)
			)
		)
		(property "Value" ""
			(at 0 0 270)
			(layer "F.Fab")
			(effects
				(font
					(size 1.27 1.27)
				)
			)
		)
		(duplicate_pad_numbers_are_jumpers no)
		(fp_line
			(start -0.7874 0.4064)
			(end -0.7874 -0.4064)
			(stroke
				(width 0.1524)
				(type default)
			)
			(layer "F.SilkS")
		)
		(fp_line
			(start 0.7874 0.4064)
			(end -0.7874 0.4064)
			(stroke
				(width 0.1524)
				(type default)
			)
			(layer "F.SilkS")
		)
		(fp_line
			(start -0.7874 -0.4064)
			(end 0.7874 -0.4064)
			(stroke
				(width 0.1524)
				(type default)
			)
			(layer "F.SilkS")
		)
		(fp_line
			(start 0.7874 -0.4064)
			(end 0.7874 0.4064)
			(stroke
				(width 0.1524)
				(type default)
			)
			(layer "F.SilkS")
		)
		(fp_line
			(start -0.67945 0.3048)
			(end -0.67945 -0.305054)
			(stroke
				(width 0.1)
				(type default)
			)
			(layer "F.Fab")
		)
		(fp_line
			(start -0.12065 0.3048)
			(end -0.67945 0.3048)
			(stroke
				(width 0.1)
				(type default)
			)
			(layer "F.Fab")
		)
		(fp_line
			(start 0.120396 0.3048)
			(end 0.120396 0.2794)
			(stroke
				(width 0.1)
				(type default)
			)
			(layer "F.Fab")
		)
		(fp_line
			(start 0.67945 0.3048)
			(end 0.120396 0.3048)
			(stroke
				(width 0.1)
				(type default)
			)
			(layer "F.Fab")
		)
		(fp_line
			(start -0.12065 0.2794)
			(end -0.12065 0.3048)
			(stroke
				(width 0.1)
				(type default)
			)
			(layer "F.Fab")
		)
		(fp_line
			(start 0.120396 0.2794)
			(end -0.12065 0.2794)
			(stroke
				(width 0.1)
				(type default)
			)
			(layer "F.Fab")
		)
		(fp_line
			(start -0.12065 -0.2794)
			(end 0.12065 -0.2794)
			(stroke
				(width 0.1)
				(type default)
			)
			(layer "F.Fab")
		)
		(fp_line
			(start 0.12065 -0.2794)
			(end 0.12065 -0.3048)
			(stroke
				(width 0.1)
				(type default)
			)
			(layer "F.Fab")
		)
		(fp_line
			(start 0.12065 -0.3048)
			(end 0.67945 -0.3048)
			(stroke
				(width 0.1)
				(type default)
			)
			(layer "F.Fab")
		)
		(fp_line
			(start 0.67945 -0.3048)
			(end 0.67945 0.3048)
			(stroke
				(width 0.1)
				(type default)
			)
			(layer "F.Fab")
		)
		(fp_line
			(start -0.67945 -0.305054)
			(end -0.12065 -0.305054)
			(stroke
				(width 0.1)
				(type default)
			)
			(layer "F.Fab")
		)
		(fp_line
			(start -0.12065 -0.305054)
			(end -0.12065 -0.2794)
			(stroke
				(width 0.1)
				(type default)
			)
			(layer "F.Fab")
		)
		(pad "1" smd circle
			(at -0.40005 0 270)
			(size 0 0)
			(layers "F.Cu" "F.Mask" "F.Paste")
			(net "SMB_BMC_MM9_R_SDA")
		)
		(pad "2" smd circle
			(at 0.40005 0 270)
			(size 0 0)
			(layers "F.Cu" "F.Mask" "F.Paste")
			(net "SMB_BMC_MM9_SDA")
		)
	)
	(footprint ""
		(layer "F.Cu")
		(at 61.51753 -34.637726 90)
		(property "Reference" "R118"
			(at 0 0 90)
			(layer "F.SilkS")
			(hide yes)
			(effects
				(font
					(size 1.27 1.27)
				)
			)
		)
		(property "Value" ""
			(at 0 0 90)
			(layer "F.Fab")
			(effects
				(font
					(size 1.27 1.27)
				)
			)
		)
		(duplicate_pad_numbers_are_jumpers no)
		(fp_line
			(start 0.7874 -0.4064)
			(end 0.7874 0.4064)
			(stroke
				(width 0.1524)
				(type default)
			)
			(layer "F.SilkS")
		)
		(fp_line
			(start -0.7874 -0.4064)
			(end 0.7874 -0.4064)
			(stroke
				(width 0.1524)
				(type default)
			)
			(layer "F.SilkS")
		)
		(fp_line
			(start 0.7874 0.4064)
			(end -0.7874 0.4064)
			(stroke
				(width 0.1524)
				(type default)
			)
			(layer "F.SilkS")
		)
		(fp_line
			(start -0.7874 0.4064)
			(end -0.7874 -0.4064)
			(stroke
				(width 0.1524)
				(type default)
			)
			(layer "F.SilkS")
		)
		(fp_line
			(start -0.12065 -0.305054)
			(end -0.12065 -0.2794)
			(stroke
				(width 0.1)
				(type default)
			)
			(layer "F.Fab")
		)
		(fp_line
			(start -0.67945 -0.305054)
			(end -0.12065 -0.305054)
			(stroke
				(width 0.1)
				(type default)
			)
			(layer "F.Fab")
		)
		(fp_line
			(start 0.67945 -0.3048)
			(end 0.67945 0.3048)
			(stroke
				(width 0.1)
				(type default)
			)
			(layer "F.Fab")
		)
		(fp_line
			(start 0.12065 -0.3048)
			(end 0.67945 -0.3048)
			(stroke
				(width 0.1)
				(type default)
			)
			(layer "F.Fab")
		)
		(fp_line
			(start 0.12065 -0.2794)
			(end 0.12065 -0.3048)
			(stroke
				(width 0.1)
				(type default)
			)
			(layer "F.Fab")
		)
		(fp_line
			(start -0.12065 -0.2794)
			(end 0.12065 -0.2794)
			(stroke
				(width 0.1)
				(type default)
			)
			(layer "F.Fab")
		)
		(fp_line
			(start 0.120396 0.2794)
			(end -0.12065 0.2794)
			(stroke
				(width 0.1)
				(type default)
			)
			(layer "F.Fab")
		)
		(fp_line
			(start -0.12065 0.2794)
			(end -0.12065 0.3048)
			(stroke
				(width 0.1)
				(type default)
			)
			(layer "F.Fab")
		)
		(fp_line
			(start 0.67945 0.3048)
			(end 0.120396 0.3048)
			(stroke
				(width 0.1)
				(type default)
			)
			(layer "F.Fab")
		)
		(fp_line
			(start 0.120396 0.3048)
			(end 0.120396 0.2794)
			(stroke
				(width 0.1)
				(type default)
			)
			(layer "F.Fab")
		)
		(fp_line
			(start -0.12065 0.3048)
			(end -0.67945 0.3048)
			(stroke
				(width 0.1)
				(type default)
			)
			(layer "F.Fab")
		)
		(fp_line
			(start -0.67945 0.3048)
			(end -0.67945 -0.305054)
			(stroke
				(width 0.1)
				(type default)
			)
			(layer "F.Fab")
		)
		(pad "1" smd circle
			(at -0.40005 0 90)
			(size 0 0)
			(layers "F.Cu" "F.Mask" "F.Paste")
			(net "GND")
		)
		(pad "2" smd circle
			(at 0.40005 0 90)
			(size 0 0)
			(layers "F.Cu" "F.Mask" "F.Paste")
			(net "RST_PLTRST_N")
		)
	)
)
